# S9S_MB_2U (Grand Teton) — schematic netlist excerpt (pin names and nets, part order shuffled) for the footprints in the layout excerpt that follows; sources: Cadence DE-HDL packaged netlist, KiCad conversion of 03242023_DA0F0TMBIJ0_F0T_Motherboard_J_brd_V01_OCP.brd

PC2365  Q_CAP  0.1UF 25V 10% EMPTY  pkg 0402  page 278 : A = PVCCD_HV_CPU0_VCC ; B = GND
PL15  Q_INDUCTOR  50NH/148A IND  pkg SMLF  page 267 : \1\ = P12V_AUX ; \2\ = SW_P12V_PVCCIN_CPU0_FLT
PC1172  Q_CAP  2.2UF 10V 10% X6S  pkg C0402  page 272 : A = PVCCFA_EHV_FIVRA_CPU0_VDD4 ; B = GND

(kicad_pcb
	(version 20260206)
	(generator "pcbnew")
	(generator_version "10.0")
	(general
		(thickness 1.6)
		(legacy_teardrops no)
	)
	(paper "A4")
	(title_block
		(title "03242023_DA0F0TMBIJ0_F0T_Motherboard_J_brd_V01_OCP.brd")
		(comment 1 "Grand Teton / footprints 3981-3983 of 6105")
	)
	(layers
		(0 "F.Cu" signal "TOP")
		(4 "In1.Cu" signal "GND")
		(6 "In2.Cu" signal "IN1")
		(8 "In3.Cu" signal "GND1")
		(10 "In4.Cu" signal "IN2")
		(12 "In5.Cu" signal "GND2")
		(14 "In6.Cu" signal "IN3")
		(16 "In7.Cu" signal "GND3")
		(18 "In8.Cu" signal "VCC")
		(20 "In9.Cu" signal "VCC1")
		(22 "In10.Cu" signal "GND4")
		(24 "In11.Cu" signal "IN4")
		(26 "In12.Cu" signal "GND5")
		(28 "In13.Cu" signal "IN5")
		(30 "In14.Cu" signal "GND6")
		(32 "In15.Cu" signal "IN6")
		(34 "In16.Cu" signal "GND7")
		(2 "B.Cu" signal "BOTTOM")
		(9 "F.Adhes" user "F.Adhesive")
		(11 "B.Adhes" user "B.Adhesive")
		(13 "F.Paste" user "Package Geometry/Pastemask Top")
		(15 "B.Paste" user "Package Geometry/Pastemask Bottom")
		(5 "F.SilkS" user "Ref Des/Silkscreen Top")
		(7 "B.SilkS" user "Ref Des/Silkscreen Bottom")
		(1 "F.Mask" user "Board Geometry/Soldermask Top")
		(3 "B.Mask" user "Board Geometry/Soldermask Bottom")
		(17 "Dwgs.User" user "User.Drawings")
		(19 "Cmts.User" user "User.Comments")
		(21 "Eco1.User" user "User.Eco1")
		(23 "Eco2.User" user "User.Eco2")
		(25 "Edge.Cuts" user "Board Geometry/Outline")
		(27 "Margin" user)
		(31 "F.CrtYd" user "Package Geometry/Place Bound Top")
		(29 "B.CrtYd" user "Package Geometry/Place Bound Bottom")
		(35 "F.Fab" user "Ref Des/Assembly Top")
		(33 "B.Fab" user "Ref Des/Assembly Bottom")
	)
	(footprint ""
		(layer "F.Cu")
		(at 340.033864 -354.332032 -90)
		(property "Reference" "PL15"
			(at -8.8011 1.901698 0)
			(unlocked yes)
			(layer "F.SilkS")
			(effects
				(font
					(size 0.7874 0.5842)
					(thickness 0.1524)
				)
				(justify left)
			)
		)
		(property "Value" ""
			(at 0 0 270)
			(layer "F.Fab")
			(effects
				(font
					(size 1.27 1.27)
				)
			)
		)
		(duplicate_pad_numbers_are_jumpers no)
		(fp_line
			(start -4.99999 4.150106)
			(end 4.99999 4.150106)
			(stroke
				(width 0.1524)
				(type default)
			)
			(layer "F.SilkS")
		)
		(fp_line
			(start 4.99999 4.150106)
			(end 4.99999 2.4892)
			(stroke
				(width 0.1524)
				(type default)
			)
			(layer "F.SilkS")
		)
		(fp_line
			(start -4.99999 2.4892)
			(end -4.99999 4.150106)
			(stroke
				(width 0.1524)
				(type default)
			)
			(layer "F.SilkS")
		)
		(fp_line
			(start 4.99999 -2.4892)
			(end 4.99999 -4.150106)
			(stroke
				(width 0.1524)
				(type default)
			)
			(layer "F.SilkS")
		)
		(fp_line
			(start -4.99999 -4.150106)
			(end -4.99999 -2.4892)
			(stroke
				(width 0.1524)
				(type default)
			)
			(layer "F.SilkS")
		)
		(fp_line
			(start 4.99999 -4.150106)
			(end -4.99999 -4.150106)
			(stroke
				(width 0.1524)
				(type default)
			)
			(layer "F.SilkS")
		)
		(fp_line
			(start -4.99999 4.150106)
			(end 4.99999 4.150106)
			(stroke
				(width 0.1)
				(type default)
			)
			(layer "F.Fab")
		)
		(fp_line
			(start 4.99999 4.150106)
			(end 4.99999 -4.150106)
			(stroke
				(width 0.1)
				(type default)
			)
			(layer "F.Fab")
		)
		(fp_line
			(start -4.99999 -4.150106)
			(end -4.99999 4.150106)
			(stroke
				(width 0.1)
				(type default)
			)
			(layer "F.Fab")
		)
		(fp_line
			(start 4.99999 -4.150106)
			(end -4.99999 -4.150106)
			(stroke
				(width 0.1)
				(type default)
			)
			(layer "F.Fab")
		)
		(pad "1" smd rect
			(at -4.174998 0 270)
			(size 2.159 4.699)
			(layers "F.Cu" "F.Mask" "F.Paste")
			(net "P12V_AUX")
		)
		(pad "2" smd rect
			(at 4.174998 0 270)
			(size 2.159 4.699)
			(layers "F.Cu" "F.Mask" "F.Paste")
			(net "SW_P12V_PVCCIN_CPU0_FLT")
		)
	)
	(footprint ""
		(layer "F.Cu")
		(at 285.211266 -365.251746 90)
		(property "Reference" "PC1172"
			(at 0 0 90)
			(layer "F.SilkS")
			(hide yes)
			(effects
				(font
					(size 1.27 1.27)
				)
			)
		)
		(property "Value" ""
			(at 0 0 90)
			(layer "F.Fab")
			(effects
				(font
					(size 1.27 1.27)
				)
			)
		)
		(duplicate_pad_numbers_are_jumpers no)
		(fp_line
			(start 0.7874 -0.4064)
			(end 0.7874 0.4064)
			(stroke
				(width 0.1524)
				(type default)
			)
			(layer "F.SilkS")
		)
		(fp_line
			(start -0.7874 -0.4064)
			(end 0.7874 -0.4064)
			(stroke
				(width 0.1524)
				(type default)
			)
			(layer "F.SilkS")
		)
		(fp_line
			(start 0.7874 0.4064)
			(end -0.7874 0.4064)
			(stroke
				(width 0.1524)
				(type default)
			)
			(layer "F.SilkS")
		)
		(fp_line
			(start -0.7874 0.4064)
			(end -0.7874 -0.4064)
			(stroke
				(width 0.1524)
				(type default)
			)
			(layer "F.SilkS")
		)
		(fp_line
			(start -0.12065 -0.305054)
			(end -0.12065 -0.2794)
			(stroke
				(width 0.1)
				(type default)
			)
			(layer "F.Fab")
		)
		(fp_line
			(start -0.67945 -0.305054)
			(end -0.12065 -0.305054)
			(stroke
				(width 0.1)
				(type default)
			)
			(layer "F.Fab")
		)
		(fp_line
			(start 0.67945 -0.3048)
			(end 0.67945 0.3048)
			(stroke
				(width 0.1)
				(type default)
			)
			(layer "F.Fab")
		)
		(fp_line
			(start 0.12065 -0.3048)
			(end 0.67945 -0.3048)
			(stroke
				(width 0.1)
				(type default)
			)
			(layer "F.Fab")
		)
		(fp_line
			(start 0.12065 -0.2794)
			(end 0.12065 -0.3048)
			(stroke
				(width 0.1)
				(type default)
			)
			(layer "F.Fab")
		)
		(fp_line
			(start -0.12065 -0.2794)
			(end 0.12065 -0.2794)
			(stroke
				(width 0.1)
				(type default)
			)
			(layer "F.Fab")
		)
		(fp_line
			(start 0.120396 0.2794)
			(end -0.12065 0.2794)
			(stroke
				(width 0.1)
				(type default)
			)
			(layer "F.Fab")
		)
		(fp_line
			(start -0.12065 0.2794)
			(end -0.12065 0.3048)
			(stroke
				(width 0.1)
				(type default)
			)
			(layer "F.Fab")
		)
		(fp_line
			(start 0.67945 0.3048)
			(end 0.120396 0.3048)
			(stroke
				(width 0.1)
				(type default)
			)
			(layer "F.Fab")
		)
		(fp_line
			(start 0.120396 0.3048)
			(end 0.120396 0.2794)
			(stroke
				(width 0.1)
				(type default)
			)
			(layer "F.Fab")
		)
		(fp_line
			(start -0.12065 0.3048)
			(end -0.67945 0.3048)
			(stroke
				(width 0.1)
				(type default)
			)
			(layer "F.Fab")
		)
		(fp_line
			(start -0.67945 0.3048)
			(end -0.67945 -0.305054)
			(stroke
				(width 0.1)
				(type default)
			)
			(layer "F.Fab")
		)
		(pad "1" smd circle
			(at -0.40005 0 90)
			(size 0 0)
			(layers "F.Cu" "F.Mask" "F.Paste")
			(net "PVCCFA_EHV_FIVRA_CPU0_VDD4")
		)
		(pad "2" smd circle
			(at 0.40005 0 90)
			(size 0 0)
			(layers "F.Cu" "F.Mask" "F.Paste")
			(net "GND")
		)
	)
	(footprint ""
		(layer "F.Cu")
		(at 428.63008 -118.34876 180)
		(property "Reference" "PC2365"
			(at 0 0 180)
			(layer "F.SilkS")
			(hide yes)
			(effects
				(font
					(size 1.27 1.27)
				)
			)
		)
		(property "Value" ""
			(at 0 0 180)
			(layer "F.Fab")
			(effects
				(font
					(size 1.27 1.27)
				)
			)
		)
		(duplicate_pad_numbers_are_jumpers no)
		(fp_line
			(start 0.7874 0.4064)
			(end -0.7874 0.4064)
			(stroke
				(width 0.1524)
				(type default)
			)
			(layer "F.SilkS")
		)
		(fp_line
			(start 0.7874 -0.4064)
			(end 0.7874 0.4064)
			(stroke
				(width 0.1524)
				(type default)
			)
			(layer "F.SilkS")
		)
		(fp_line
			(start -0.7874 0.4064)
			(end -0.7874 -0.4064)
			(stroke
				(width 0.1524)
				(type default)
			)
			(layer "F.SilkS")
		)
		(fp_line
			(start -0.7874 -0.4064)
			(end 0.7874 -0.4064)
			(stroke
				(width 0.1524)
				(type default)
			)
			(layer "F.SilkS")
		)
		(fp_line
			(start 0.67945 0.3048)
			(end 0.120396 0.3048)
			(stroke
				(width 0.1)
				(type default)
			)
			(layer "F.Fab")
		)
		(fp_line
			(start 0.67945 -0.3048)
			(end 0.67945 0.3048)
			(stroke
				(width 0.1)
				(type default)
			)
			(layer "F.Fab")
		)
		(fp_line
			(start 0.12065 -0.2794)
			(end 0.12065 -0.3048)
			(stroke
				(width 0.1)
				(type default)
			)
			(layer "F.Fab")
		)
		(fp_line
			(start 0.12065 -0.3048)
			(end 0.67945 -0.3048)
			(stroke
				(width 0.1)
				(type default)
			)
			(layer "F.Fab")
		)
		(fp_line
			(start 0.120396 0.3048)
			(end 0.120396 0.2794)
			(stroke
				(width 0.1)
				(type default)
			)
			(layer "F.Fab")
		)
		(fp_line
			(start 0.120396 0.2794)
			(end -0.12065 0.2794)
			(stroke
				(width 0.1)
				(type default)
			)
			(layer "F.Fab")
		)
		(fp_line
			(start -0.12065 0.3048)
			(end -0.67945 0.3048)
			(stroke
				(width 0.1)
				(type default)
			)
			(layer "F.Fab")
		)
		(fp_line
			(start -0.12065 0.2794)
			(end -0.12065 0.3048)
			(stroke
				(width 0.1)
				(type default)
			)
			(layer "F.Fab")
		)
		(fp_line
			(start -0.12065 -0.2794)
			(end 0.12065 -0.2794)
			(stroke
				(width 0.1)
				(type default)
			)
			(layer "F.Fab")
		)
		(fp_line
			(start -0.12065 -0.305054)
			(end -0.12065 -0.2794)
			(stroke
				(width 0.1)
				(type default)
			)
			(layer "F.Fab")
		)
		(fp_line
			(start -0.67945 0.3048)
			(end -0.67945 -0.305054)
			(stroke
				(width 0.1)
				(type default)
			)
			(layer "F.Fab")
		)
		(fp_line
			(start -0.67945 -0.305054)
			(end -0.12065 -0.305054)
			(stroke
				(width 0.1)
				(type default)
			)
			(layer "F.Fab")
		)
		(pad "1" smd circle
			(at -0.40005 0 180)
			(size 0 0)
			(layers "F.Cu" "F.Mask" "F.Paste")
			(net "PVCCD_HV_CPU0_VCC")
		)
		(pad "2" smd circle
			(at 0.40005 0 180)
			(size 0 0)
			(layers "F.Cu" "F.Mask" "F.Paste")
			(net "GND")
		)
	)
)
